#ISCELL
  mstr_symbols intel_corp_bpage *
  *
#ISCELL
  mstr_symbols gnd *
  page127_i14
#ISCELL
  mstr_symbols p1v05_pch_stby *
  page127_i16
#CELL
  mstr_discrete ferrite *
  page127_i17
#CELL
  dev_discrete cap_a *
  page127_i18
#ISCELL
  mstr_symbols gnd *
  page127_i23
#ISCELL
  mstr_symbols p1v05_pch_stby *
  page127_i25
#CELL
  mstr_discrete ferrite *
  page127_i26
#CELL
  dev_discrete cap_a *
  page127_i27
#ISCELL
  mstr_symbols gnd *
  page127_i32
#ISCELL
  mstr_symbols gnd *
  page127_i34
#ISCELL
  mstr_symbols gnd *
  page127_i36
#ISCELL
  mstr_symbols p1v05_pch_stby_vcca_xtal *
  page127_i39
#ISCELL
  mstr_symbols p1v05_pch_stby_wm20_pll *
  page127_i40
#CELL
  mstr_discrete cap *
  page127_i43
#CELL
  dev_discrete cap_a *
  page127_i44
#ISCELL
  mstr_symbols p1v05_pch_stby *
  page127_i45
#CELL
  mstr_discrete ferrite *
  page127_i46
#ISCELL
  mstr_symbols p1v05_pch_stby_wm26_pll *
  page127_i47
#CELL
  mstr_discrete cap *
  page127_i49
#CELL
  dev_discrete cap_a *
  page127_i50
#ISCELL
  mstr_symbols gnd *
  page127_i51
#ISCELL
  mstr_symbols p1v05_pch_stby_isclk_pll *
  page127_i52
#ISCELL
  mstr_symbols p1v05_pch_stby *
  page127_i55
#CELL
  mstr_discrete ferrite *
  page127_i56
#CELL
  dev_discrete cap_a *
  page127_i57
#ISCELL
  mstr_symbols gnd *
  page127_i58
#ISCELL
  mstr_symbols gnd *
  page127_i59
#ISCELL
  mstr_symbols gnd *
  page127_i6
#ISCELL
  mstr_symbols gnd *
  page127_i61
#ISCELL
  mstr_symbols p1v05_pch_stby_kr_pll *
  page127_i62
#CELL
  mstr_discrete cap *
  page127_i64
#CELL
  dev_discrete cap_a *
  page127_i65
#ISCELL
  mstr_symbols gnd *
  page127_i66
#ISCELL
  mstr_symbols p1v05_pch_stby *
  page127_i68
#CELL
  mstr_discrete ferrite *
  page127_i69
#ISCELL
  mstr_symbols p1v05_pch_stby *
  page127_i7
#ISCELL
  mstr_symbols p1v05_pch_stby *
  page127_i70
#CELL
  mstr_discrete inductor *
  page127_i71
#ISCELL
  mstr_symbols p1v05_pch_stby_vcca_pll0 *
  page127_i72
#ISCELL
  mstr_symbols p1v05_pch_stby_vcca_pll1 *
  page127_i73
#CELL
  dev_discrete cap_a *
  page127_i74
#ISCELL
  mstr_symbols gnd *
  page127_i75
#CELL
  dev_discrete cap_a *
  page127_i76
#ISCELL
  mstr_symbols gnd *
  page127_i77
#CELL
  dev_discrete cap_a *
  page127_i78
#ISCELL
  mstr_symbols gnd *
  page127_i79
#CELL
  mstr_discrete ferrite *
  page127_i8
#CELL
  dev_discrete cap_a *
  page127_i80
#CELL
  mstr_discrete cap *
  page127_i81
#CELL
  mstr_discrete cap *
  page127_i82
#CELL
  dev_discrete cap_a *
  page127_i83
#CELL
  dev_discrete cap_a *
  page127_i84
#CELL
  mstr_discrete cap *
  page127_i85
#CELL
  mstr_discrete cap *
  page127_i86
#CELL
  dev_discrete cap_a *
  page127_i87
#CELL
  dev_discrete cap_a *
  page127_i9
